#ISCELL
  mstr_misc dns *
  *
#ISCELL
  pure_quanta quanta_title_block_c *
  *
#ISCELL
  logical_power universal_gnd *
  page219_i1
#CELL
  pure_quanta q_res *
  page219_i10
#ISCELL
  standard offpage *
  page219_i11
#ISCELL
  standard offpage *
  page219_i12
#ISCELL
  standard offpage *
  page219_i13
#ISCELL
  standard offpage *
  page219_i14
#ISCELL
  standard offpage *
  page219_i15
#ISCELL
  standard offpage *
  page219_i16
#ISCELL
  standard offpage *
  page219_i17
#CELL
  pure_quanta q_res *
  page219_i18
#ISCELL
  logical_power universal_power *
  page219_i19
#CELL
  pure_quanta q_res *
  page219_i2
#CELL
  pure_quanta q_res *
  page219_i20
#CELL
  pure_quanta q_res *
  page219_i21
#CELL
  pure_quanta q_res *
  page219_i22
#CELL
  pure_quanta q_res *
  page219_i23
#CELL
  pure_quanta q_res *
  page219_i24
#CELL
  pure_quanta q_res *
  page219_i25
#ISCELL
  standard offpage *
  page219_i26
#ISCELL
  standard offpage *
  page219_i27
#ISCELL
  standard offpage *
  page219_i28
#ISCELL
  standard offpage *
  page219_i29
#CELL
  pure_quanta q_res *
  page219_i3
#ISCELL
  standard offpage *
  page219_i30
#ISCELL
  standard offpage *
  page219_i31
#ISCELL
  standard offpage *
  page219_i32
#ISCELL
  standard offpage *
  page219_i33
#ISCELL
  standard offpage *
  page219_i34
#CELL
  pure_quanta q_res *
  page219_i35
#CELL
  pure_quanta q_res *
  page219_i36
#CELL
  pure_quanta q_res *
  page219_i37
#CELL
  pure_quanta q_res *
  page219_i38
#CELL
  pure_quanta q_res *
  page219_i39
#ISCELL
  logical_power universal_power *
  page219_i4
#CELL
  pure_quanta q_res *
  page219_i40
#CELL
  pure_quanta q_res *
  page219_i41
#ISCELL
  standard offpage *
  page219_i42
#ISCELL
  standard offpage *
  page219_i43
#ISCELL
  standard offpage *
  page219_i44
#CELL
  pure_quanta tca9548apwr *
  page219_i45
#ISCELL
  logical_power universal_gnd *
  page219_i46
#CELL
  pure_quanta q_cap *
  page219_i47
#ISCELL
  logical_power universal_power *
  page219_i48
#CELL
  pure_quanta q_res *
  page219_i49
#ISCELL
  logical_power universal_gnd *
  page219_i5
#CELL
  pure_quanta q_res *
  page219_i50
#CELL
  pure_quanta q_res *
  page219_i51
#CELL
  pure_quanta q_res *
  page219_i52
#CELL
  pure_quanta q_res *
  page219_i53
#CELL
  pure_quanta q_res *
  page219_i54
#ISCELL
  logical_power universal_power *
  page219_i55
#CELL
  pure_quanta q_res *
  page219_i56
#CELL
  pure_quanta q_res *
  page219_i57
#ISCELL
  logical_power universal_gnd *
  page219_i58
#CELL
  pure_quanta q_res *
  page219_i59
#CELL
  pure_quanta q_res *
  page219_i6
#CELL
  pure_quanta q_res *
  page219_i60
#CELL
  pure_quanta q_res *
  page219_i61
#CELL
  pure_quanta q_res *
  page219_i62
#CELL
  pure_quanta q_res *
  page219_i63
#CELL
  pure_quanta q_res *
  page219_i64
#CELL
  pure_quanta q_res *
  page219_i65
#CELL
  pure_quanta q_res *
  page219_i66
#ISCELL
  standard offpage *
  page219_i67
#ISCELL
  standard offpage *
  page219_i68
#ISCELL
  standard offpage *
  page219_i69
#ISCELL
  logical_power universal_gnd *
  page219_i7
#ISCELL
  standard offpage *
  page219_i70
#ISCELL
  standard offpage *
  page219_i71
#ISCELL
  standard offpage *
  page219_i72
#ISCELL
  standard offpage *
  page219_i73
#ISCELL
  standard offpage *
  page219_i74
#ISCELL
  standard offpage *
  page219_i75
#ISCELL
  standard offpage *
  page219_i76
#ISCELL
  standard offpage *
  page219_i77
#ISCELL
  standard offpage *
  page219_i78
#ISCELL
  standard offpage *
  page219_i79
#CELL
  pure_quanta q_res *
  page219_i8
#ISCELL
  standard offpage *
  page219_i80
#ISCELL
  standard offpage *
  page219_i81
#ISCELL
  standard offpage *
  page219_i82
#CELL
  pure_quanta q_res *
  page219_i9
